# T6G (Grand Teton) — schematic netlist excerpt (pin names and nets, part order shuffled) for the footprints in the layout excerpt that follows; sources: Cadence DE-HDL packaged netlist, KiCad conversion of 04192023_DAF0TMB3IC0_F0TG_MB_C_brd_V02_OCP.brd

J64  PICOPROBE_BXA  DELTA-L 4.0 EMPTY  pkg TRIANG_LAUNCH_3PXB  page 229
  \1_p\  = DELTA_L_85_5INCH_BOT_DP
  \2_n\  = DELTA_L_85_5INCH_BOT_DN
  \3_g\  = DELTA_L_GND_1

(kicad_pcb
	(version 20260206)
	(generator "pcbnew")
	(generator_version "10.0")
	(general
		(thickness 1.6)
		(legacy_teardrops no)
	)
	(paper "A4")
	(title_block
		(title "04192023_DAF0TMB3IC0_F0TG_MB_C_brd_V02_OCP.brd")
		(comment 1 "Grand Teton / footprints 6797-6797 of 8354")
	)
	(layers
		(0 "F.Cu" signal "TOP")
		(4 "In1.Cu" signal "GND")
		(6 "In2.Cu" signal "IN1")
		(8 "In3.Cu" signal "GND1")
		(10 "In4.Cu" signal "IN2")
		(12 "In5.Cu" signal "GND2")
		(14 "In6.Cu" signal "IN3")
		(16 "In7.Cu" signal "GND3")
		(18 "In8.Cu" signal "VCC")
		(20 "In9.Cu" signal "VCC1")
		(22 "In10.Cu" signal "GND4")
		(24 "In11.Cu" signal "IN4")
		(26 "In12.Cu" signal "GND5")
		(28 "In13.Cu" signal "IN5")
		(30 "In14.Cu" signal "GND6")
		(32 "In15.Cu" signal "IN6")
		(34 "In16.Cu" signal "GND7")
		(2 "B.Cu" signal "BOTTOM")
		(9 "F.Adhes" user "F.Adhesive")
		(11 "B.Adhes" user "B.Adhesive")
		(13 "F.Paste" user "Package Geometry/Pastemask Top")
		(15 "B.Paste" user "Package Geometry/Pastemask Bottom")
		(5 "F.SilkS" user "Ref Des/Silkscreen Top")
		(7 "B.SilkS" user "Ref Des/Silkscreen Bottom")
		(1 "F.Mask" user "Board Geometry/Soldermask Top")
		(3 "B.Mask" user "Board Geometry/Soldermask Bottom")
		(17 "Dwgs.User" user "User.Drawings")
		(19 "Cmts.User" user "User.Comments")
		(21 "Eco1.User" user "User.Eco1")
		(23 "Eco2.User" user "User.Eco2")
		(25 "Edge.Cuts" user "Board Geometry/Outline")
		(27 "Margin" user)
		(31 "F.CrtYd" user "Package Geometry/Place Bound Top")
		(29 "B.CrtYd" user "Package Geometry/Place Bound Bottom")
		(35 "F.Fab" user "Ref Des/Assembly Top")
		(33 "B.Fab" user "Ref Des/Assembly Bottom")
	)
	(footprint ""
		(layer "B.Cu")
		(at 366.288574 2.542794)
		(property "Reference" "J64"
			(at 4.258818 1.085596 270)
			(unlocked yes)
			(layer "B.SilkS")
			(effects
				(font
					(size 0.7874 0.5842)
					(thickness 0.1524)
				)
				(justify left mirror)
			)
		)
		(property "Value" ""
			(at 0 0 0)
			(layer "B.Fab")
			(effects
				(font
					(size 1.27 1.27)
				)
				(justify mirror)
			)
		)
		(duplicate_pad_numbers_are_jumpers no)
		(fp_line
			(start -1.2192 -2.06756)
			(end -1.2192 2.06756)
			(stroke
				(width 0.1524)
				(type default)
			)
			(layer "B.SilkS")
		)
		(fp_line
			(start -1.2192 2.06756)
			(end 1.2192 2.06756)
			(stroke
				(width 0.1524)
				(type default)
			)
			(layer "B.SilkS")
		)
		(fp_line
			(start 1.2192 -2.06756)
			(end -1.2192 -2.06756)
			(stroke
				(width 0.1524)
				(type default)
			)
			(layer "B.SilkS")
		)
		(fp_line
			(start 1.2192 2.06756)
			(end 1.2192 -2.06756)
			(stroke
				(width 0.1524)
				(type default)
			)
			(layer "B.SilkS")
		)
		(pad "" np_thru_hole circle
			(at -3.4671 -1.27 270)
			(size 1.0414 1.0414)
			(drill 1.0414)
			(layers "*.Cu" "*.Mask")
			(clearance 0.381)
			(thermal_gap 0.381)
		)
		(pad "" np_thru_hole circle
			(at -3.4671 1.27 270)
			(size 1.0414 1.0414)
			(drill 1.0414)
			(layers "*.Cu" "*.Mask")
			(clearance 0.381)
			(thermal_gap 0.381)
		)
		(pad "" np_thru_hole circle
			(at 2.8829 -1.27 270)
			(size 1.0414 1.0414)
			(drill 1.0414)
			(layers "*.Cu" "*.Mask")
			(clearance 0.381)
			(thermal_gap 0.381)
		)
		(pad "" np_thru_hole circle
			(at 2.8829 1.27 270)
			(size 1.0414 1.0414)
			(drill 1.0414)
			(layers "*.Cu" "*.Mask")
			(clearance 0.381)
			(thermal_gap 0.381)
		)
		(pad "1" smd rect
			(at -0.8255 -0.249936 270)
			(size 0.3048 0.508)
			(layers "B.Cu" "B.Mask" "B.Paste")
			(net "DELTA_L_85_5INCH_BOT_DP")
		)
		(pad "2" smd rect
			(at -0.8255 0.249936 270)
			(size 0.3048 0.508)
			(layers "B.Cu" "B.Mask" "B.Paste")
			(net "DELTA_L_85_5INCH_BOT_DN")
		)
		(pad "3" smd circle
			(at 0 0 180)
			(size 0 0)
			(layers "B.Cu" "B.Mask" "B.Paste")
			(net "DELTA_L_GND_1")
		)
		(zone
			(layers "F.Cu" "B.Cu" "In1.Cu" "In2.Cu" "In3.Cu" "In4.Cu" "In5.Cu" "In6.Cu"
				"In7.Cu" "In8.Cu" "In9.Cu" "In10.Cu" "In11.Cu" "In12.Cu" "In13.Cu" "In14.Cu"
				"In15.Cu" "In16.Cu"
			)
			(hatch none 0.5)
			(connect_pads
				(clearance 0)
			)
			(min_thickness 0.25)
			(keepout
				(tracks not_allowed)
				(vias allowed)
				(pads allowed)
				(copperpour not_allowed)
				(footprints allowed)
			)
			(placement
				(enabled no)
				(sheetname "")
			)
			(fill
				(thermal_gap 0.5)
				(thermal_bridge_width 0.5)
				(island_removal_mode 0)
			)
			(polygon
				(pts
					(arc
						(start 363.748574 1.272794)
						(mid 361.894374 1.272794)
						(end 363.748574 1.272794)
					)
				)
			)
		)
		(zone
			(layers "F.Cu" "B.Cu" "In1.Cu" "In2.Cu" "In3.Cu" "In4.Cu" "In5.Cu" "In6.Cu"
				"In7.Cu" "In8.Cu" "In9.Cu" "In10.Cu" "In11.Cu" "In12.Cu" "In13.Cu" "In14.Cu"
				"In15.Cu" "In16.Cu"
			)
			(hatch none 0.5)
			(connect_pads
				(clearance 0)
			)
			(min_thickness 0.25)
			(keepout
				(tracks not_allowed)
				(vias allowed)
				(pads allowed)
				(copperpour not_allowed)
				(footprints allowed)
			)
			(placement
				(enabled no)
				(sheetname "")
			)
			(fill
				(thermal_gap 0.5)
				(thermal_bridge_width 0.5)
				(island_removal_mode 0)
			)
			(polygon
				(pts
					(arc
						(start 363.748574 3.812794)
						(mid 361.894374 3.812794)
						(end 363.748574 3.812794)
					)
				)
			)
		)
		(zone
			(layers "F.Cu" "B.Cu" "In1.Cu" "In2.Cu" "In3.Cu" "In4.Cu" "In5.Cu" "In6.Cu"
				"In7.Cu" "In8.Cu" "In9.Cu" "In10.Cu" "In11.Cu" "In12.Cu" "In13.Cu" "In14.Cu"
				"In15.Cu" "In16.Cu"
			)
			(hatch none 0.5)
			(connect_pads
				(clearance 0)
			)
			(min_thickness 0.25)
			(keepout
				(tracks not_allowed)
				(vias allowed)
				(pads allowed)
				(copperpour not_allowed)
				(footprints allowed)
			)
			(placement
				(enabled no)
				(sheetname "")
			)
			(fill
				(thermal_gap 0.5)
				(thermal_bridge_width 0.5)
				(island_removal_mode 0)
			)
			(polygon
				(pts
					(arc
						(start 370.098574 1.272794)
						(mid 368.244374 1.272794)
						(end 370.098574 1.272794)
					)
				)
			)
		)
		(zone
			(layers "F.Cu" "B.Cu" "In1.Cu" "In2.Cu" "In3.Cu" "In4.Cu" "In5.Cu" "In6.Cu"
				"In7.Cu" "In8.Cu" "In9.Cu" "In10.Cu" "In11.Cu" "In12.Cu" "In13.Cu" "In14.Cu"
				"In15.Cu" "In16.Cu"
			)
			(hatch none 0.5)
			(connect_pads
				(clearance 0)
			)
			(min_thickness 0.25)
			(keepout
				(tracks not_allowed)
				(vias allowed)
				(pads allowed)
				(copperpour not_allowed)
				(footprints allowed)
			)
			(placement
				(enabled no)
				(sheetname "")
			)
			(fill
				(thermal_gap 0.5)
				(thermal_bridge_width 0.5)
				(island_removal_mode 0)
			)
			(polygon
				(pts
					(arc
						(start 370.098574 3.812794)
						(mid 368.244374 3.812794)
						(end 370.098574 3.812794)
					)
				)
			)
		)
		(zone
			(layer "B.Cu")
			(hatch none 0.5)
			(connect_pads
				(clearance 0)
			)
			(min_thickness 0.25)
			(keepout
				(tracks not_allowed)
				(vias allowed)
				(pads allowed)
				(copperpour not_allowed)
				(footprints allowed)
			)
			(placement
				(enabled no)
				(sheetname "")
			)
			(fill
				(thermal_gap 0.5)
				(thermal_bridge_width 0.5)
				(island_removal_mode 0)
			)
			(polygon
				(pts
					(xy 365.170974 1.994154) (xy 365.170974 2.089658) (xy 365.767874 2.089658) (xy 365.767874 2.496058)
					(xy 365.170974 2.496058) (xy 365.170974 2.58953) (xy 365.767874 2.58953) (xy 365.767874 2.99593)
					(xy 365.170974 2.99593) (xy 365.170974 3.091434) (xy 365.869474 3.091434) (xy 365.869474 1.994154)
				)
			)
		)
	)
)
